(kicad_pcb
	(version 20260206)
	(generator "pcbnew")
	(generator_version "10.0")
	(general
		(thickness 1.6)
		(legacy_teardrops no)
	)
	(paper "A4")
	(title_block
		(title "03242023_DA0F0TMBIJ0_F0T_Motherboard_J_brd_V01_OCP.brd")
		(comment 1 "Grand Teton / footprints 293-296 of 6105")
	)
	(layers
		(0 "F.Cu" signal "TOP")
		(4 "In1.Cu" signal "GND")
		(6 "In2.Cu" signal "IN1")
		(8 "In3.Cu" signal "GND1")
		(10 "In4.Cu" signal "IN2")
		(12 "In5.Cu" signal "GND2")
		(14 "In6.Cu" signal "IN3")
		(16 "In7.Cu" signal "GND3")
		(18 "In8.Cu" signal "VCC")
		(20 "In9.Cu" signal "VCC1")
		(22 "In10.Cu" signal "GND4")
		(24 "In11.Cu" signal "IN4")
		(26 "In12.Cu" signal "GND5")
		(28 "In13.Cu" signal "IN5")
		(30 "In14.Cu" signal "GND6")
		(32 "In15.Cu" signal "IN6")
		(34 "In16.Cu" signal "GND7")
		(2 "B.Cu" signal "BOTTOM")
		(9 "F.Adhes" user "F.Adhesive")
		(11 "B.Adhes" user "B.Adhesive")
		(13 "F.Paste" user "Package Geometry/Pastemask Top")
		(15 "B.Paste" user "Package Geometry/Pastemask Bottom")
		(5 "F.SilkS" user "Ref Des/Silkscreen Top")
		(7 "B.SilkS" user "Ref Des/Silkscreen Bottom")
		(1 "F.Mask" user "Board Geometry/Soldermask Top")
		(3 "B.Mask" user "Board Geometry/Soldermask Bottom")
		(17 "Dwgs.User" user "User.Drawings")
		(19 "Cmts.User" user "User.Comments")
		(21 "Eco1.User" user "User.Eco1")
		(23 "Eco2.User" user "User.Eco2")
		(25 "Edge.Cuts" user "Board Geometry/Outline")
		(27 "Margin" user)
		(31 "F.CrtYd" user "Package Geometry/Place Bound Top")
		(29 "B.CrtYd" user "Package Geometry/Place Bound Bottom")
		(35 "F.Fab" user "Ref Des/Assembly Top")
		(33 "B.Fab" user "Ref Des/Assembly Bottom")
	)
	(footprint ""
		(layer "F.Cu")
		(at 141.656054 -97.808542 -90)
		(property "Reference" "U306"
			(at -1.20523 -2.996692 0)
			(unlocked yes)
			(layer "F.SilkS")
			(effects
				(font
					(size 0.7874 0.5842)
					(thickness 0.1524)
				)
				(justify left)
			)
		)
		(property "Value" ""
			(at 0 0 270)
			(layer "F.Fab")
			(effects
				(font
					(size 1.27 1.27)
				)
			)
		)
		(duplicate_pad_numbers_are_jumpers no)
		(fp_line
			(start -2.0066 2.5527)
			(end -2.0066 -2.5527)
			(stroke
				(width 0.1524)
				(type default)
			)
			(layer "F.SilkS")
		)
		(fp_line
			(start 2.0066 2.5527)
			(end -2.0066 2.5527)
			(stroke
				(width 0.1524)
				(type default)
			)
			(layer "F.SilkS")
		)
		(fp_line
			(start 0 -1.9812)
			(end 0.5715 -2.5527)
			(stroke
				(width 0.1524)
				(type default)
			)
			(layer "F.SilkS")
		)
		(fp_line
			(start -2.0066 -2.5527)
			(end -0.5715 -2.5527)
			(stroke
				(width 0.1524)
				(type default)
			)
			(layer "F.SilkS")
		)
		(fp_line
			(start -0.5715 -2.5527)
			(end 0 -1.9812)
			(stroke
				(width 0.1524)
				(type default)
			)
			(layer "F.SilkS")
		)
		(fp_line
			(start 0.5715 -2.5527)
			(end 2.0066 -2.5527)
			(stroke
				(width 0.1524)
				(type default)
			)
			(layer "F.SilkS")
		)
		(fp_line
			(start 2.0066 -2.5527)
			(end 2.0066 2.5527)
			(stroke
				(width 0.1524)
				(type default)
			)
			(layer "F.SilkS")
		)
		(fp_poly
			(pts
				(xy -2.810764 -2.90576) (xy -3.138932 -2.35204) (xy -3.435604 -2.90576)
			)
			(stroke
				(width 0)
				(type default)
			)
			(fill yes)
			(layer "F.SilkS")
		)
		(fp_line
			(start -2.249932 2.549906)
			(end -2.249932 -2.549906)
			(stroke
				(width 0.1)
				(type default)
			)
			(layer "F.Fab")
		)
		(fp_line
			(start 2.249932 2.549906)
			(end -2.249932 2.549906)
			(stroke
				(width 0.1)
				(type default)
			)
			(layer "F.Fab")
		)
		(fp_line
			(start -2.249932 -2.549906)
			(end 2.249932 -2.549906)
			(stroke
				(width 0.1)
				(type default)
			)
			(layer "F.Fab")
		)
		(fp_line
			(start 2.249932 -2.549906)
			(end 2.249932 2.549906)
			(stroke
				(width 0.1)
				(type default)
			)
			(layer "F.Fab")
		)
		(fp_poly
			(pts
				(xy -4.36372 -1.608328) (xy -4.36372 -2.233168) (xy -3.81 -1.905)
			)
			(stroke
				(width 0)
				(type default)
			)
			(fill yes)
			(layer "F.Fab")
		)
		(pad "1" smd rect
			(at -2.921 -1.949958 180)
			(size 0.3556 1.4986)
			(layers "F.Cu" "F.Mask" "F.Paste")
			(net "PD_CPU1_ERRS_U306_DIR")
		)
		(pad "2" smd rect
			(at -2.921 -1.299972 180)
			(size 0.3556 1.4986)
			(layers "F.Cu" "F.Mask" "F.Paste")
			(net "PD_GTL2014_ERROR_B0")
		)
		(pad "3" smd rect
			(at -2.921 -0.649986 180)
			(size 0.3556 1.4986)
			(layers "F.Cu" "F.Mask" "F.Paste")
			(net "H_CPU_ERR2_LVC1_N")
		)
		(pad "4" smd rect
			(at -2.921 0 180)
			(size 0.3556 1.4986)
			(layers "F.Cu" "F.Mask" "F.Paste")
			(net "P0V62_CPU0_ERRS_U306_VREF")
		)
		(pad "5" smd rect
			(at -2.921 0.649986 180)
			(size 0.3556 1.4986)
			(layers "F.Cu" "F.Mask" "F.Paste")
			(net "H_CPU_ERR1_LVC1_N")
		)
		(pad "6" smd rect
			(at -2.921 1.299972 180)
			(size 0.3556 1.4986)
			(layers "F.Cu" "F.Mask" "F.Paste")
			(net "H_CPU_ERR0_LVC1_N")
		)
		(pad "7" smd rect
			(at -2.921 1.949958 180)
			(size 0.3556 1.4986)
			(layers "F.Cu" "F.Mask" "F.Paste")
			(net "GND")
		)
		(pad "8" smd rect
			(at 2.921 1.949958 180)
			(size 0.3556 1.4986)
			(layers "F.Cu" "F.Mask" "F.Paste")
			(net "GND")
		)
		(pad "9" smd rect
			(at 2.921 1.299972 180)
			(size 0.3556 1.4986)
			(layers "F.Cu" "F.Mask" "F.Paste")
			(net "H_CPU_ERR0_LVC2_R_N")
		)
		(pad "10" smd rect
			(at 2.921 0.649986 180)
			(size 0.3556 1.4986)
			(layers "F.Cu" "F.Mask" "F.Paste")
			(net "H_CPU_ERR1_LVC2_R_N")
		)
		(pad "11" smd rect
			(at 2.921 0 180)
			(size 0.3556 1.4986)
			(layers "F.Cu" "F.Mask" "F.Paste")
			(net "GND")
		)
		(pad "12" smd rect
			(at 2.921 -0.649986 180)
			(size 0.3556 1.4986)
			(layers "F.Cu" "F.Mask" "F.Paste")
			(net "H_CPU_ERR2_LVC2_R_N")
		)
		(pad "13" smd rect
			(at 2.921 -1.299972 180)
			(size 0.3556 1.4986)
			(layers "F.Cu" "F.Mask" "F.Paste")
			(net "NC_U306_A0")
		)
		(pad "14" smd rect
			(at 2.921 -1.949958 180)
			(size 0.3556 1.4986)
			(layers "F.Cu" "F.Mask" "F.Paste")
			(net "P3V3")
		)
	)
	(footprint ""
		(layer "F.Cu")
		(at 349.77705 -360.929174 -90)
		(property "Reference" "R2366"
			(at 0 0 270)
			(layer "F.SilkS")
			(hide yes)
			(effects
				(font
					(size 1.27 1.27)
				)
			)
		)
		(property "Value" ""
			(at 0 0 270)
			(layer "F.Fab")
			(effects
				(font
					(size 1.27 1.27)
				)
			)
		)
		(duplicate_pad_numbers_are_jumpers no)
		(fp_line
			(start -0.7874 0.4064)
			(end -0.7874 -0.4064)
			(stroke
				(width 0.1524)
				(type default)
			)
			(layer "F.SilkS")
		)
		(fp_line
			(start 0.7874 0.4064)
			(end -0.7874 0.4064)
			(stroke
				(width 0.1524)
				(type default)
			)
			(layer "F.SilkS")
		)
		(fp_line
			(start -0.7874 -0.4064)
			(end 0.7874 -0.4064)
			(stroke
				(width 0.1524)
				(type default)
			)
			(layer "F.SilkS")
		)
		(fp_line
			(start 0.7874 -0.4064)
			(end 0.7874 0.4064)
			(stroke
				(width 0.1524)
				(type default)
			)
			(layer "F.SilkS")
		)
		(fp_line
			(start -0.67945 0.3048)
			(end -0.67945 -0.305054)
			(stroke
				(width 0.1)
				(type default)
			)
			(layer "F.Fab")
		)
		(fp_line
			(start -0.12065 0.3048)
			(end -0.67945 0.3048)
			(stroke
				(width 0.1)
				(type default)
			)
			(layer "F.Fab")
		)
		(fp_line
			(start 0.120396 0.3048)
			(end 0.120396 0.2794)
			(stroke
				(width 0.1)
				(type default)
			)
			(layer "F.Fab")
		)
		(fp_line
			(start 0.67945 0.3048)
			(end 0.120396 0.3048)
			(stroke
				(width 0.1)
				(type default)
			)
			(layer "F.Fab")
		)
		(fp_line
			(start -0.12065 0.2794)
			(end -0.12065 0.3048)
			(stroke
				(width 0.1)
				(type default)
			)
			(layer "F.Fab")
		)
		(fp_line
			(start 0.120396 0.2794)
			(end -0.12065 0.2794)
			(stroke
				(width 0.1)
				(type default)
			)
			(layer "F.Fab")
		)
		(fp_line
			(start -0.12065 -0.2794)
			(end 0.12065 -0.2794)
			(stroke
				(width 0.1)
				(type default)
			)
			(layer "F.Fab")
		)
		(fp_line
			(start 0.12065 -0.2794)
			(end 0.12065 -0.3048)
			(stroke
				(width 0.1)
				(type default)
			)
			(layer "F.Fab")
		)
		(fp_line
			(start 0.12065 -0.3048)
			(end 0.67945 -0.3048)
			(stroke
				(width 0.1)
				(type default)
			)
			(layer "F.Fab")
		)
		(fp_line
			(start 0.67945 -0.3048)
			(end 0.67945 0.3048)
			(stroke
				(width 0.1)
				(type default)
			)
			(layer "F.Fab")
		)
		(fp_line
			(start -0.67945 -0.305054)
			(end -0.12065 -0.305054)
			(stroke
				(width 0.1)
				(type default)
			)
			(layer "F.Fab")
		)
		(fp_line
			(start -0.12065 -0.305054)
			(end -0.12065 -0.2794)
			(stroke
				(width 0.1)
				(type default)
			)
			(layer "F.Fab")
		)
		(pad "1" smd circle
			(at -0.40005 0 270)
			(size 0 0)
			(layers "F.Cu" "F.Mask" "F.Paste")
			(net "PWRGD_PVCCIN_CPU0")
		)
		(pad "2" smd circle
			(at 0.40005 0 270)
			(size 0 0)
			(layers "F.Cu" "F.Mask" "F.Paste")
			(net "PWRGD_PVCCIN_CPU0_R")
		)
	)
	(footprint ""
		(layer "F.Cu")
		(at 344.937588 -333.716122)
		(property "Reference" "PU13_P0_1"
			(at -2.66954 -6.20649 0)
			(unlocked yes)
			(layer "F.SilkS")
			(effects
				(font
					(size 0.7874 0.5842)
					(thickness 0.1524)
				)
				(justify left)
			)
		)
		(property "Value" ""
			(at 0 0 0)
			(layer "F.Fab")
			(effects
				(font
					(size 1.27 1.27)
				)
			)
		)
		(duplicate_pad_numbers_are_jumpers no)
		(fp_line
			(start -2.500122 -2.999994)
			(end -2.24409 -2.999994)
			(stroke
				(width 0.1524)
				(type default)
			)
			(layer "F.SilkS")
		)
		(fp_line
			(start -2.500122 -2.529078)
			(end -2.500122 -2.999994)
			(stroke
				(width 0.1524)
				(type default)
			)
			(layer "F.SilkS")
		)
		(fp_line
			(start -2.500122 0.6604)
			(end -2.500122 0.229108)
			(stroke
				(width 0.1524)
				(type default)
			)
			(layer "F.SilkS")
		)
		(fp_line
			(start -2.500122 2.999994)
			(end -2.500122 2.339594)
			(stroke
				(width 0.1524)
				(type default)
			)
			(layer "F.SilkS")
		)
		(fp_line
			(start -2.2987 2.999994)
			(end -2.500122 2.999994)
			(stroke
				(width 0.1524)
				(type default)
			)
			(layer "F.SilkS")
		)
		(fp_line
			(start 2.31394 -2.999994)
			(end 2.500122 -2.999994)
			(stroke
				(width 0.1524)
				(type default)
			)
			(layer "F.SilkS")
		)
		(fp_line
			(start 2.500122 -2.999994)
			(end 2.500122 -2.44348)
			(stroke
				(width 0.1524)
				(type default)
			)
			(layer "F.SilkS")
		)
		(fp_line
			(start 2.500122 2.339594)
			(end 2.500122 2.999994)
			(stroke
				(width 0.1524)
				(type default)
			)
			(layer "F.SilkS")
		)
		(fp_line
			(start 2.500122 2.999994)
			(end 2.2987 2.999994)
			(stroke
				(width 0.1524)
				(type default)
			)
			(layer "F.SilkS")
		)
		(fp_poly
			(pts
				(xy -2.218436 -3.60045) (xy -2.726436 -2.58445) (xy -3.234436 -3.60045)
			)
			(stroke
				(width 0)
				(type default)
			)
			(fill yes)
			(layer "F.SilkS")
		)
		(fp_line
			(start -2.500122 -2.999994)
			(end 2.500122 -2.999994)
			(stroke
				(width 0.1)
				(type default)
			)
			(layer "F.Fab")
		)
		(fp_line
			(start -2.500122 2.999994)
			(end -2.500122 -2.999994)
			(stroke
				(width 0.1)
				(type default)
			)
			(layer "F.Fab")
		)
		(fp_line
			(start 2.500122 -2.999994)
			(end 2.500122 2.999994)
			(stroke
				(width 0.1)
				(type default)
			)
			(layer "F.Fab")
		)
		(fp_line
			(start 2.500122 2.999994)
			(end -2.500122 2.999994)
			(stroke
				(width 0.1)
				(type default)
			)
			(layer "F.Fab")
		)
		(fp_poly
			(pts
				(xy -4.218432 -2.783078) (xy -4.218432 -1.767078) (xy -3.202432 -2.275078)
			)
			(stroke
				(width 0)
				(type default)
			)
			(fill yes)
			(layer "F.Fab")
		)
		(pad "1" smd rect
			(at -2.400046 -2.275078 90)
			(size 0.2286 0.6096)
			(layers "F.Cu" "F.Mask" "F.Paste")
			(net "PVCCIN_CPU0_VOS1")
		)
		(pad "2" smd rect
			(at -2.400046 -1.82499 90)
			(size 0.2286 0.6096)
			(layers "F.Cu" "F.Mask" "F.Paste")
			(net "GND")
		)
		(pad "3" smd rect
			(at -2.400046 -1.374902 90)
			(size 0.2286 0.6096)
			(layers "F.Cu" "F.Mask" "F.Paste")
			(net "PVCCIN_CPU0_VDD1")
		)
		(pad "4" smd rect
			(at -2.400046 -0.925068 90)
			(size 0.2286 0.6096)
			(layers "F.Cu" "F.Mask" "F.Paste")
			(net "PVCCIN_CPU0_PVCC")
		)
		(pad "5" smd rect
			(at -2.400046 -0.47498 90)
			(size 0.2286 0.6096)
			(layers "F.Cu" "F.Mask" "F.Paste")
			(net "GND")
		)
		(pad "6" smd rect
			(at -2.400046 -0.024892 90)
			(size 0.2286 0.6096)
			(layers "F.Cu" "F.Mask" "F.Paste")
			(net "Net_8544")
		)
		(pad "7_9-20_24" smd circle
			(at 0 1.150112 90)
			(size 0 0)
			(layers "F.Cu" "F.Mask" "F.Paste")
			(net "GND")
		)
		(pad "10_19" smd rect
			(at 0 2.899918 90)
			(size 0.6096 4.318)
			(layers "F.Cu" "F.Mask" "F.Paste")
			(net "SW_PVCCIN_CPU0_SW1")
		)
		(pad "25_29" smd rect
			(at 1.549908 -1.279906 270)
			(size 2.0574 2.3114)
			(layers "F.Cu" "F.Mask" "F.Paste")
			(net "SW_P12V_PVCCIN_CPU0_FLT")
		)
		(pad "30" smd rect
			(at 2.05994 -2.899918)
			(size 0.2286 0.6096)
			(layers "F.Cu" "F.Mask" "F.Paste")
			(net "SW_P12V_PVCCIN_CPU0_FLT")
		)
		(pad "31" smd rect
			(at 1.610106 -2.899918)
			(size 0.2286 0.6096)
			(layers "F.Cu" "F.Mask" "F.Paste")
			(net "Net_8545")
		)
		(pad "32" smd rect
			(at 1.160018 -2.899918)
			(size 0.2286 0.6096)
			(layers "F.Cu" "F.Mask" "F.Paste")
			(net "SW_PVCCIN_CPU0_BOOTR1")
		)
		(pad "33" smd rect
			(at 0.70993 -2.899918)
			(size 0.2286 0.6096)
			(layers "F.Cu" "F.Mask" "F.Paste")
			(net "SW_PVCCIN_CPU0_BOOT1")
		)
		(pad "34" smd rect
			(at 0.260096 -2.899918)
			(size 0.2286 0.6096)
			(layers "F.Cu" "F.Mask" "F.Paste")
			(net "PVCCIN_CPU0_PWM1")
		)
		(pad "35" smd rect
			(at -0.189992 -2.899918)
			(size 0.2286 0.6096)
			(layers "F.Cu" "F.Mask" "F.Paste")
			(net "PVCCIN_CPU0_VDD1")
		)
		(pad "36" smd rect
			(at -0.64008 -2.899918)
			(size 0.2286 0.6096)
			(layers "F.Cu" "F.Mask" "F.Paste")
			(net "PVCCIN_CPU0_ATSEN")
		)
		(pad "37" smd rect
			(at -1.089914 -2.899918)
			(size 0.2286 0.6096)
			(layers "F.Cu" "F.Mask" "F.Paste")
			(net "PVCCIN_CPU0_LSET1")
		)
		(pad "38" smd rect
			(at -1.540002 -2.899918)
			(size 0.2286 0.6096)
			(layers "F.Cu" "F.Mask" "F.Paste")
			(net "PVCCIN_CPU0_IMON1")
		)
		(pad "39" smd rect
			(at -1.99009 -2.899918)
			(size 0.2286 0.6096)
			(layers "F.Cu" "F.Mask" "F.Paste")
			(net "PVCCIN_CPU0_VREF")
		)
		(pad "40" smd rect
			(at -0.87503 -1.27508)
			(size 1.7526 1.9558)
			(layers "F.Cu" "F.Mask" "F.Paste")
			(net "GND")
		)
		(pad "41" smd rect
			(at -1.525016 0.249936 270)
			(size 0.3048 0.4572)
			(layers "F.Cu" "F.Mask" "F.Paste")
			(net "Net_8543")
		)
		(zone
			(layer "F.Cu")
			(hatch none 0.5)
			(connect_pads
				(clearance 0)
			)
			(min_thickness 0.25)
			(keepout
				(tracks not_allowed)
				(vias allowed)
				(pads allowed)
				(copperpour not_allowed)
				(footprints allowed)
			)
			(placement
				(enabled no)
				(sheetname "")
			)
			(fill
				(thermal_gap 0.5)
				(thermal_bridge_width 0.5)
				(island_removal_mode 0)
			)
			(polygon
				(pts
					(xy 342.437466 -330.716128) (xy 342.437466 -331.465428) (xy 347.43771 -331.465428) (xy 347.43771 -330.716128)
					(xy 347.147388 -330.716128) (xy 347.147388 -331.171804) (xy 342.727788 -331.171804) (xy 342.727788 -330.716128)
				)
			)
		)
		(zone
			(layer "F.Cu")
			(hatch none 0.5)
			(connect_pads
				(clearance 0)
			)
			(min_thickness 0.25)
			(keepout
				(tracks not_allowed)
				(vias allowed)
				(pads allowed)
				(copperpour not_allowed)
				(footprints allowed)
			)
			(placement
				(enabled no)
				(sheetname "")
			)
			(fill
				(thermal_gap 0.5)
				(thermal_bridge_width 0.5)
				(island_removal_mode 0)
			)
			(polygon
				(pts
					(xy 343.691972 -333.634588) (xy 343.986866 -333.634588) (xy 343.986866 -332.966822) (xy 342.437466 -332.966822)
					(xy 342.437466 -333.423514) (xy 343.133172 -333.423514) (xy 343.133172 -333.262986) (xy 343.691972 -333.262986)
				)
			)
		)
	)
	(footprint ""
		(layer "F.Cu")
		(at 68.212462 -40.437562)
		(property "Reference" "R3608"
			(at 0 0 0)
			(layer "F.SilkS")
			(hide yes)
			(effects
				(font
					(size 1.27 1.27)
				)
			)
		)
		(property "Value" ""
			(at 0 0 0)
			(layer "F.Fab")
			(effects
				(font
					(size 1.27 1.27)
				)
			)
		)
		(duplicate_pad_numbers_are_jumpers no)
		(fp_line
			(start -0.7874 -0.4064)
			(end 0.7874 -0.4064)
			(stroke
				(width 0.1524)
				(type default)
			)
			(layer "F.SilkS")
		)
		(fp_line
			(start -0.7874 0.4064)
			(end -0.7874 -0.4064)
			(stroke
				(width 0.1524)
				(type default)
			)
			(layer "F.SilkS")
		)
		(fp_line
			(start 0.7874 -0.4064)
			(end 0.7874 0.4064)
			(stroke
				(width 0.1524)
				(type default)
			)
			(layer "F.SilkS")
		)
		(fp_line
			(start 0.7874 0.4064)
			(end -0.7874 0.4064)
			(stroke
				(width 0.1524)
				(type default)
			)
			(layer "F.SilkS")
		)
		(fp_line
			(start -0.67945 -0.305054)
			(end -0.12065 -0.305054)
			(stroke
				(width 0.1)
				(type default)
			)
			(layer "F.Fab")
		)
		(fp_line
			(start -0.67945 0.3048)
			(end -0.67945 -0.305054)
			(stroke
				(width 0.1)
				(type default)
			)
			(layer "F.Fab")
		)
		(fp_line
			(start -0.12065 -0.305054)
			(end -0.12065 -0.2794)
			(stroke
				(width 0.1)
				(type default)
			)
			(layer "F.Fab")
		)
		(fp_line
			(start -0.12065 -0.2794)
			(end 0.12065 -0.2794)
			(stroke
				(width 0.1)
				(type default)
			)
			(layer "F.Fab")
		)
		(fp_line
			(start -0.12065 0.2794)
			(end -0.12065 0.3048)
			(stroke
				(width 0.1)
				(type default)
			)
			(layer "F.Fab")
		)
		(fp_line
			(start -0.12065 0.3048)
			(end -0.67945 0.3048)
			(stroke
				(width 0.1)
				(type default)
			)
			(layer "F.Fab")
		)
		(fp_line
			(start 0.120396 0.2794)
			(end -0.12065 0.2794)
			(stroke
				(width 0.1)
				(type default)
			)
			(layer "F.Fab")
		)
		(fp_line
			(start 0.120396 0.3048)
			(end 0.120396 0.2794)
			(stroke
				(width 0.1)
				(type default)
			)
			(layer "F.Fab")
		)
		(fp_line
			(start 0.12065 -0.3048)
			(end 0.67945 -0.3048)
			(stroke
				(width 0.1)
				(type default)
			)
			(layer "F.Fab")
		)
		(fp_line
			(start 0.12065 -0.2794)
			(end 0.12065 -0.3048)
			(stroke
				(width 0.1)
				(type default)
			)
			(layer "F.Fab")
		)
		(fp_line
			(start 0.67945 -0.3048)
			(end 0.67945 0.3048)
			(stroke
				(width 0.1)
				(type default)
			)
			(layer "F.Fab")
		)
		(fp_line
			(start 0.67945 0.3048)
			(end 0.120396 0.3048)
			(stroke
				(width 0.1)
				(type default)
			)
			(layer "F.Fab")
		)
		(pad "1" smd circle
			(at -0.40005 0)
			(size 0 0)
			(layers "F.Cu" "F.Mask" "F.Paste")
			(net "GND")
		)
		(pad "2" smd circle
			(at 0.40005 0)
			(size 0 0)
			(layers "F.Cu" "F.Mask" "F.Paste")
			(net "INA230_3_A1")
		)
	)
)
